# S9S_MB_2U (Grand Teton) — schematic netlist excerpt (pin names and nets, part order shuffled) for the footprints in the layout excerpt that follows; sources: Cadence DE-HDL packaged netlist, KiCad conversion of 03242023_DA0F0TMBIJ0_F0T_Motherboard_J_brd_V01_OCP.brd

R4082  Q_RES  10K 1% EMPTY  pkg 0402LF  page 212 : A = CLK_GEN2_SMB_SADR ; B = GND
PC460  Q_CAPP  270UF 16V 20% OSCON  pkg THLF  page 293 : A = SW_P12V_PVCCINFAON_CPU1_FLT ; B = GND
R2380  Q_RES  0 5% CHIP  pkg 0402LF  page 299 : A = PWRGD_PVPP_HBM_CPU1_R ; B = PWRGD_PVPP_HBM_CPU1

(kicad_pcb
	(version 20260206)
	(generator "pcbnew")
	(generator_version "10.0")
	(general
		(thickness 1.6)
		(legacy_teardrops no)
	)
	(paper "A4")
	(title_block
		(title "03242023_DA0F0TMBIJ0_F0T_Motherboard_J_brd_V01_OCP.brd")
		(comment 1 "Grand Teton / footprints 2530-2532 of 6105")
	)
	(layers
		(0 "F.Cu" signal "TOP")
		(4 "In1.Cu" signal "GND")
		(6 "In2.Cu" signal "IN1")
		(8 "In3.Cu" signal "GND1")
		(10 "In4.Cu" signal "IN2")
		(12 "In5.Cu" signal "GND2")
		(14 "In6.Cu" signal "IN3")
		(16 "In7.Cu" signal "GND3")
		(18 "In8.Cu" signal "VCC")
		(20 "In9.Cu" signal "VCC1")
		(22 "In10.Cu" signal "GND4")
		(24 "In11.Cu" signal "IN4")
		(26 "In12.Cu" signal "GND5")
		(28 "In13.Cu" signal "IN5")
		(30 "In14.Cu" signal "GND6")
		(32 "In15.Cu" signal "IN6")
		(34 "In16.Cu" signal "GND7")
		(2 "B.Cu" signal "BOTTOM")
		(9 "F.Adhes" user "F.Adhesive")
		(11 "B.Adhes" user "B.Adhesive")
		(13 "F.Paste" user "Package Geometry/Pastemask Top")
		(15 "B.Paste" user "Package Geometry/Pastemask Bottom")
		(5 "F.SilkS" user "Ref Des/Silkscreen Top")
		(7 "B.SilkS" user "Ref Des/Silkscreen Bottom")
		(1 "F.Mask" user "Board Geometry/Soldermask Top")
		(3 "B.Mask" user "Board Geometry/Soldermask Bottom")
		(17 "Dwgs.User" user "User.Drawings")
		(19 "Cmts.User" user "User.Comments")
		(21 "Eco1.User" user "User.Eco1")
		(23 "Eco2.User" user "User.Eco2")
		(25 "Edge.Cuts" user "Board Geometry/Outline")
		(27 "Margin" user)
		(31 "F.CrtYd" user "Package Geometry/Place Bound Top")
		(29 "B.CrtYd" user "Package Geometry/Place Bound Bottom")
		(35 "F.Fab" user "Ref Des/Assembly Top")
		(33 "B.Fab" user "Ref Des/Assembly Bottom")
	)
	(footprint ""
		(layer "F.Cu")
		(at 243.78666 -253.363984)
		(property "Reference" "R4082"
			(at 0 0 0)
			(layer "F.SilkS")
			(hide yes)
			(effects
				(font
					(size 1.27 1.27)
				)
			)
		)
		(property "Value" ""
			(at 0 0 0)
			(layer "F.Fab")
			(effects
				(font
					(size 1.27 1.27)
				)
			)
		)
		(duplicate_pad_numbers_are_jumpers no)
		(fp_line
			(start -0.7874 -0.4064)
			(end 0.7874 -0.4064)
			(stroke
				(width 0.1524)
				(type default)
			)
			(layer "F.SilkS")
		)
		(fp_line
			(start -0.7874 0.4064)
			(end -0.7874 -0.4064)
			(stroke
				(width 0.1524)
				(type default)
			)
			(layer "F.SilkS")
		)
		(fp_line
			(start 0.7874 -0.4064)
			(end 0.7874 0.4064)
			(stroke
				(width 0.1524)
				(type default)
			)
			(layer "F.SilkS")
		)
		(fp_line
			(start 0.7874 0.4064)
			(end -0.7874 0.4064)
			(stroke
				(width 0.1524)
				(type default)
			)
			(layer "F.SilkS")
		)
		(fp_line
			(start -0.67945 -0.305054)
			(end -0.12065 -0.305054)
			(stroke
				(width 0.1)
				(type default)
			)
			(layer "F.Fab")
		)
		(fp_line
			(start -0.67945 0.3048)
			(end -0.67945 -0.305054)
			(stroke
				(width 0.1)
				(type default)
			)
			(layer "F.Fab")
		)
		(fp_line
			(start -0.12065 -0.305054)
			(end -0.12065 -0.2794)
			(stroke
				(width 0.1)
				(type default)
			)
			(layer "F.Fab")
		)
		(fp_line
			(start -0.12065 -0.2794)
			(end 0.12065 -0.2794)
			(stroke
				(width 0.1)
				(type default)
			)
			(layer "F.Fab")
		)
		(fp_line
			(start -0.12065 0.2794)
			(end -0.12065 0.3048)
			(stroke
				(width 0.1)
				(type default)
			)
			(layer "F.Fab")
		)
		(fp_line
			(start -0.12065 0.3048)
			(end -0.67945 0.3048)
			(stroke
				(width 0.1)
				(type default)
			)
			(layer "F.Fab")
		)
		(fp_line
			(start 0.120396 0.2794)
			(end -0.12065 0.2794)
			(stroke
				(width 0.1)
				(type default)
			)
			(layer "F.Fab")
		)
		(fp_line
			(start 0.120396 0.3048)
			(end 0.120396 0.2794)
			(stroke
				(width 0.1)
				(type default)
			)
			(layer "F.Fab")
		)
		(fp_line
			(start 0.12065 -0.3048)
			(end 0.67945 -0.3048)
			(stroke
				(width 0.1)
				(type default)
			)
			(layer "F.Fab")
		)
		(fp_line
			(start 0.12065 -0.2794)
			(end 0.12065 -0.3048)
			(stroke
				(width 0.1)
				(type default)
			)
			(layer "F.Fab")
		)
		(fp_line
			(start 0.67945 -0.3048)
			(end 0.67945 0.3048)
			(stroke
				(width 0.1)
				(type default)
			)
			(layer "F.Fab")
		)
		(fp_line
			(start 0.67945 0.3048)
			(end 0.120396 0.3048)
			(stroke
				(width 0.1)
				(type default)
			)
			(layer "F.Fab")
		)
		(pad "1" smd circle
			(at -0.40005 0)
			(size 0 0)
			(layers "F.Cu" "F.Mask" "F.Paste")
			(net "CLK_GEN2_SMB_SADR")
		)
		(pad "2" smd circle
			(at 0.40005 0)
			(size 0 0)
			(layers "F.Cu" "F.Mask" "F.Paste")
			(net "GND")
		)
	)
	(footprint ""
		(layer "F.Cu")
		(at 44.295822 -172.301916)
		(property "Reference" "PC460"
			(at 0 0 0)
			(layer "F.SilkS")
			(hide yes)
			(effects
				(font
					(size 1.27 1.27)
				)
			)
		)
		(property "Value" ""
			(at 0 0 0)
			(layer "F.Fab")
			(effects
				(font
					(size 1.27 1.27)
				)
			)
		)
		(duplicate_pad_numbers_are_jumpers no)
		(fp_line
			(start -3.400044 1.249934)
			(end 3.400044 1.249934)
			(stroke
				(width 0.1524)
				(type default)
			)
			(layer "F.SilkS")
		)
		(fp_circle
			(center 0 1.249934)
			(end 3.400044 1.249934)
			(stroke
				(width 0.1524)
				(type default)
			)
			(fill no)
			(layer "F.SilkS")
		)
		(fp_poly
			(pts
				(arc
					(start -3.400044 1.249934)
					(mid 0 4.649978)
					(end 3.400044 1.249934)
				)
			)
			(stroke
				(width 0)
				(type default)
			)
			(fill yes)
			(layer "F.SilkS")
		)
		(fp_circle
			(center 0 1.249934)
			(end 3.400044 1.249934)
			(stroke
				(width 0.1)
				(type default)
			)
			(fill no)
			(layer "F.Fab")
		)
		(pad "1" thru_hole rect
			(at 0 0)
			(size 1.524 1.524)
			(drill 1.016)
			(layers "*.Cu" "*.Mask")
			(remove_unused_layers no)
			(net "SW_P12V_PVCCINFAON_CPU1_FLT")
			(clearance 0)
			(padstack
				(mode front_inner_back)
				(layer "Inner"
					(shape circle)
					(size 1.524 1.524)
					(clearance 0)
				)
				(layer "B.Cu"
					(shape rect)
					(size 1.524 1.524)
					(clearance 0)
				)
			)
		)
		(pad "2" thru_hole circle
			(at 0 2.500122)
			(size 1.524 1.524)
			(drill 1.016)
			(layers "*.Cu" "*.Mask")
			(remove_unused_layers no)
			(net "GND")
			(clearance 0)
		)
	)
	(footprint ""
		(layer "F.Cu")
		(at 119.333264 -354.737924 180)
		(property "Reference" "R2380"
			(at 0 0 180)
			(layer "F.SilkS")
			(hide yes)
			(effects
				(font
					(size 1.27 1.27)
				)
			)
		)
		(property "Value" ""
			(at 0 0 180)
			(layer "F.Fab")
			(effects
				(font
					(size 1.27 1.27)
				)
			)
		)
		(duplicate_pad_numbers_are_jumpers no)
		(fp_line
			(start 0.7874 0.4064)
			(end -0.7874 0.4064)
			(stroke
				(width 0.1524)
				(type default)
			)
			(layer "F.SilkS")
		)
		(fp_line
			(start 0.7874 -0.4064)
			(end 0.7874 0.4064)
			(stroke
				(width 0.1524)
				(type default)
			)
			(layer "F.SilkS")
		)
		(fp_line
			(start -0.7874 0.4064)
			(end -0.7874 -0.4064)
			(stroke
				(width 0.1524)
				(type default)
			)
			(layer "F.SilkS")
		)
		(fp_line
			(start -0.7874 -0.4064)
			(end 0.7874 -0.4064)
			(stroke
				(width 0.1524)
				(type default)
			)
			(layer "F.SilkS")
		)
		(fp_line
			(start 0.67945 0.3048)
			(end 0.120396 0.3048)
			(stroke
				(width 0.1)
				(type default)
			)
			(layer "F.Fab")
		)
		(fp_line
			(start 0.67945 -0.3048)
			(end 0.67945 0.3048)
			(stroke
				(width 0.1)
				(type default)
			)
			(layer "F.Fab")
		)
		(fp_line
			(start 0.12065 -0.2794)
			(end 0.12065 -0.3048)
			(stroke
				(width 0.1)
				(type default)
			)
			(layer "F.Fab")
		)
		(fp_line
			(start 0.12065 -0.3048)
			(end 0.67945 -0.3048)
			(stroke
				(width 0.1)
				(type default)
			)
			(layer "F.Fab")
		)
		(fp_line
			(start 0.120396 0.3048)
			(end 0.120396 0.2794)
			(stroke
				(width 0.1)
				(type default)
			)
			(layer "F.Fab")
		)
		(fp_line
			(start 0.120396 0.2794)
			(end -0.12065 0.2794)
			(stroke
				(width 0.1)
				(type default)
			)
			(layer "F.Fab")
		)
		(fp_line
			(start -0.12065 0.3048)
			(end -0.67945 0.3048)
			(stroke
				(width 0.1)
				(type default)
			)
			(layer "F.Fab")
		)
		(fp_line
			(start -0.12065 0.2794)
			(end -0.12065 0.3048)
			(stroke
				(width 0.1)
				(type default)
			)
			(layer "F.Fab")
		)
		(fp_line
			(start -0.12065 -0.2794)
			(end 0.12065 -0.2794)
			(stroke
				(width 0.1)
				(type default)
			)
			(layer "F.Fab")
		)
		(fp_line
			(start -0.12065 -0.305054)
			(end -0.12065 -0.2794)
			(stroke
				(width 0.1)
				(type default)
			)
			(layer "F.Fab")
		)
		(fp_line
			(start -0.67945 0.3048)
			(end -0.67945 -0.305054)
			(stroke
				(width 0.1)
				(type default)
			)
			(layer "F.Fab")
		)
		(fp_line
			(start -0.67945 -0.305054)
			(end -0.12065 -0.305054)
			(stroke
				(width 0.1)
				(type default)
			)
			(layer "F.Fab")
		)
		(pad "1" smd circle
			(at -0.40005 0 180)
			(size 0 0)
			(layers "F.Cu" "F.Mask" "F.Paste")
			(net "PWRGD_PVPP_HBM_CPU1_R")
		)
		(pad "2" smd circle
			(at 0.40005 0 180)
			(size 0 0)
			(layers "F.Cu" "F.Mask" "F.Paste")
			(net "PWRGD_PVPP_HBM_CPU1")
		)
	)
)
